(kicad_pcb
	(version 20260206)
	(generator "pcbnew")
	(generator_version "10.0")
	(general
		(thickness 1.6)
		(legacy_teardrops no)
	)
	(paper "A4")
	(title_block
		(title "v1-chassis-manager — T6M_CM_d_v01_1031_1645.brd")
		(comment 1 "Open CloudServer (Microsoft) / footprints 963-971 of 2512")
	)
	(layers
		(0 "F.Cu" signal "TOP")
		(4 "In1.Cu" signal "GND1")
		(6 "In2.Cu" signal "IN1")
		(8 "In3.Cu" signal "VCC1")
		(10 "In4.Cu" signal "VCC2")
		(12 "In5.Cu" signal "GND2")
		(14 "In6.Cu" signal "IN2")
		(16 "In7.Cu" signal "IN3")
		(18 "In8.Cu" signal "GND3")
		(2 "B.Cu" signal "BOTTOM")
		(9 "F.Adhes" user "F.Adhesive")
		(11 "B.Adhes" user "B.Adhesive")
		(13 "F.Paste" user "Package Geometry/Pastemask Top")
		(15 "B.Paste" user "Package Geometry/Pastemask Bottom")
		(5 "F.SilkS" user "Ref Des/Silkscreen Top")
		(7 "B.SilkS" user "Ref Des/Silkscreen Bottom")
		(1 "F.Mask" user "Board Geometry/Soldermask Top")
		(3 "B.Mask" user "Board Geometry/Soldermask Bottom")
		(17 "Dwgs.User" user "User.Drawings")
		(19 "Cmts.User" user "User.Comments")
		(21 "Eco1.User" user "User.Eco1")
		(23 "Eco2.User" user "User.Eco2")
		(25 "Edge.Cuts" user "Board Geometry/Outline")
		(27 "Margin" user)
		(31 "F.CrtYd" user "Package Geometry/Place Bound Top")
		(29 "B.CrtYd" user "Package Geometry/Place Bound Bottom")
		(35 "F.Fab" user "Ref Des/Assembly Top")
		(33 "B.Fab" user "Ref Des/Assembly Bottom")
	)
	(footprint ""
		(layer "F.Cu")
		(at 140.069316 -25.812242 -90)
		(property "Reference" "R1139"
			(at 10.732008 -4.259326 90)
			(unlocked yes)
			(layer "F.SilkS")
			(effects
				(font
					(size 0.7874 0.5842)
					(thickness 0.1524)
				)
				(justify left)
			)
		)
		(property "Value" ""
			(at 0 0 270)
			(layer "F.Fab")
			(effects
				(font
					(size 1.27 1.27)
				)
			)
		)
		(duplicate_pad_numbers_are_jumpers no)
		(fp_line
			(start -0.7874 0.4064)
			(end -0.7874 -0.4064)
			(stroke
				(width 0.1524)
				(type default)
			)
			(layer "F.SilkS")
		)
		(fp_line
			(start 0.7874 0.4064)
			(end -0.7874 0.4064)
			(stroke
				(width 0.1524)
				(type default)
			)
			(layer "F.SilkS")
		)
		(fp_line
			(start -0.7874 -0.4064)
			(end 0.7874 -0.4064)
			(stroke
				(width 0.1524)
				(type default)
			)
			(layer "F.SilkS")
		)
		(fp_line
			(start 0.7874 -0.4064)
			(end 0.7874 0.4064)
			(stroke
				(width 0.1524)
				(type default)
			)
			(layer "F.SilkS")
		)
		(fp_poly
			(pts
				(xy -0.508 0.2794) (xy -0.508 0.2286) (xy -0.635 0.2286) (xy -0.635 -0.254) (xy -0.5334 -0.254)
				(xy -0.5334 -0.2794) (xy 0.5334 -0.2794) (xy 0.5334 -0.254) (xy 0.635 -0.254) (xy 0.635 0.254) (xy 0.5334 0.254)
				(xy 0.5334 0.2794)
			)
			(stroke
				(width 0)
				(type default)
			)
			(fill no)
			(layer "F.CrtYd")
		)
		(pad "1" smd rect
			(at 0.40005 0 270)
			(size 0.4572 0.508)
			(layers "F.Cu" "F.Mask" "F.Paste")
			(net "P3V3_NODE1")
		)
		(pad "2" smd rect
			(at -0.40005 0 270)
			(size 0.4572 0.508)
			(layers "F.Cu" "F.Mask" "F.Paste")
			(net "UART_DSR_P6_N")
		)
	)
	(footprint ""
		(layer "F.Cu")
		(at 94.467426 -167.162734)
		(property "Reference" "C577"
			(at 86.63305 73.147936 0)
			(unlocked yes)
			(layer "F.SilkS")
			(effects
				(font
					(size 0.7874 0.5842)
					(thickness 0.1524)
				)
				(justify left)
			)
		)
		(property "Value" ""
			(at 0 0 0)
			(layer "F.Fab")
			(effects
				(font
					(size 1.27 1.27)
				)
			)
		)
		(duplicate_pad_numbers_are_jumpers no)
		(fp_line
			(start -0.7874 -0.4064)
			(end 0.7874 -0.4064)
			(stroke
				(width 0.1524)
				(type default)
			)
			(layer "F.SilkS")
		)
		(fp_line
			(start -0.7874 0.4064)
			(end -0.7874 -0.4064)
			(stroke
				(width 0.1524)
				(type default)
			)
			(layer "F.SilkS")
		)
		(fp_line
			(start 0 0.381)
			(end 0 -0.381)
			(stroke
				(width 0.1524)
				(type default)
			)
			(layer "F.SilkS")
		)
		(fp_line
			(start 0.7874 -0.4064)
			(end 0.7874 0.4064)
			(stroke
				(width 0.1524)
				(type default)
			)
			(layer "F.SilkS")
		)
		(fp_line
			(start 0.7874 0.4064)
			(end -0.7874 0.4064)
			(stroke
				(width 0.1524)
				(type default)
			)
			(layer "F.SilkS")
		)
		(fp_poly
			(pts
				(xy -0.5334 0.254) (xy -0.635 0.254) (xy -0.635 0.2286) (xy -0.635 -0.254) (xy -0.5334 -0.254) (xy -0.5334 -0.2794)
				(xy 0.5334 -0.2794) (xy 0.5334 -0.254) (xy 0.635 -0.254) (xy 0.635 0.254) (xy 0.5334 0.254) (xy 0.5334 0.2794)
				(xy -0.508 0.2794) (xy -0.5334 0.2794)
			)
			(stroke
				(width 0)
				(type default)
			)
			(fill no)
			(layer "F.CrtYd")
		)
		(pad "1" smd rect
			(at 0.40005 0)
			(size 0.4572 0.508)
			(layers "F.Cu" "F.Mask" "F.Paste")
			(net "P3V3_NODE1")
		)
		(pad "2" smd rect
			(at -0.40005 0)
			(size 0.4572 0.508)
			(layers "F.Cu" "F.Mask" "F.Paste")
			(net "GND")
		)
	)
	(footprint ""
		(layer "F.Cu")
		(at 54.344062 -152.643078)
		(property "Reference" "C391"
			(at -2.277872 -2.017522 0)
			(unlocked yes)
			(layer "F.SilkS")
			(effects
				(font
					(size 0.7874 0.5842)
					(thickness 0.1524)
				)
				(justify left)
			)
		)
		(property "Value" ""
			(at 0 0 0)
			(layer "F.Fab")
			(effects
				(font
					(size 1.27 1.27)
				)
			)
		)
		(duplicate_pad_numbers_are_jumpers no)
		(fp_line
			(start -0.7874 -0.4064)
			(end 0.7874 -0.4064)
			(stroke
				(width 0.1524)
				(type default)
			)
			(layer "F.SilkS")
		)
		(fp_line
			(start -0.7874 0.4064)
			(end -0.7874 -0.4064)
			(stroke
				(width 0.1524)
				(type default)
			)
			(layer "F.SilkS")
		)
		(fp_line
			(start 0 0.381)
			(end 0 -0.381)
			(stroke
				(width 0.1524)
				(type default)
			)
			(layer "F.SilkS")
		)
		(fp_line
			(start 0.7874 -0.4064)
			(end 0.7874 0.4064)
			(stroke
				(width 0.1524)
				(type default)
			)
			(layer "F.SilkS")
		)
		(fp_line
			(start 0.7874 0.4064)
			(end -0.7874 0.4064)
			(stroke
				(width 0.1524)
				(type default)
			)
			(layer "F.SilkS")
		)
		(fp_poly
			(pts
				(xy -0.5334 0.254) (xy -0.635 0.254) (xy -0.635 0.2286) (xy -0.635 -0.254) (xy -0.5334 -0.254) (xy -0.5334 -0.2794)
				(xy 0.5334 -0.2794) (xy 0.5334 -0.254) (xy 0.635 -0.254) (xy 0.635 0.254) (xy 0.5334 0.254) (xy 0.5334 0.2794)
				(xy -0.508 0.2794) (xy -0.5334 0.2794)
			)
			(stroke
				(width 0)
				(type default)
			)
			(fill no)
			(layer "F.CrtYd")
		)
		(pad "1" smd rect
			(at 0.40005 0)
			(size 0.4572 0.508)
			(layers "F.Cu" "F.Mask" "F.Paste")
			(net "P2E_CPU_NIC1_NODE1_RX_DP")
		)
		(pad "2" smd rect
			(at -0.40005 0)
			(size 0.4572 0.508)
			(layers "F.Cu" "F.Mask" "F.Paste")
			(net "PCIE_LAN1_RX_C_DP")
		)
	)
	(footprint ""
		(layer "F.Cu")
		(at 37.885878 -14.22527 -90)
		(property "Reference" "PR103"
			(at 0.98171 3.471926 90)
			(unlocked yes)
			(layer "F.SilkS")
			(effects
				(font
					(size 0.7874 0.5842)
					(thickness 0.1524)
				)
				(justify left)
			)
		)
		(property "Value" ""
			(at 0 0 270)
			(layer "F.Fab")
			(effects
				(font
					(size 1.27 1.27)
				)
			)
		)
		(duplicate_pad_numbers_are_jumpers no)
		(fp_line
			(start -0.7874 0.4064)
			(end -0.7874 -0.4064)
			(stroke
				(width 0.1524)
				(type default)
			)
			(layer "F.SilkS")
		)
		(fp_line
			(start 0.7874 0.4064)
			(end -0.7874 0.4064)
			(stroke
				(width 0.1524)
				(type default)
			)
			(layer "F.SilkS")
		)
		(fp_line
			(start -0.7874 -0.4064)
			(end 0.7874 -0.4064)
			(stroke
				(width 0.1524)
				(type default)
			)
			(layer "F.SilkS")
		)
		(fp_line
			(start 0.7874 -0.4064)
			(end 0.7874 0.4064)
			(stroke
				(width 0.1524)
				(type default)
			)
			(layer "F.SilkS")
		)
		(fp_poly
			(pts
				(xy -0.508 0.2794) (xy -0.508 0.2286) (xy -0.635 0.2286) (xy -0.635 -0.254) (xy -0.5334 -0.254)
				(xy -0.5334 -0.2794) (xy 0.5334 -0.2794) (xy 0.5334 -0.254) (xy 0.635 -0.254) (xy 0.635 0.254) (xy 0.5334 0.254)
				(xy 0.5334 0.2794)
			)
			(stroke
				(width 0)
				(type default)
			)
			(fill no)
			(layer "F.CrtYd")
		)
		(pad "1" smd rect
			(at 0.40005 0 270)
			(size 0.4572 0.508)
			(layers "F.Cu" "F.Mask" "F.Paste")
			(net "PV_VDDR_NODE1_TRIP")
		)
		(pad "2" smd rect
			(at -0.40005 0 270)
			(size 0.4572 0.508)
			(layers "F.Cu" "F.Mask" "F.Paste")
			(net "GND")
		)
	)
	(footprint ""
		(layer "F.Cu")
		(at 166.73322 -124.88291 180)
		(property "Reference" "R1050"
			(at 2.81559 -9.851644 0)
			(unlocked yes)
			(layer "F.SilkS")
			(effects
				(font
					(size 0.7874 0.5842)
					(thickness 0.1524)
				)
				(justify left)
			)
		)
		(property "Value" ""
			(at 0 0 180)
			(layer "F.Fab")
			(effects
				(font
					(size 1.27 1.27)
				)
			)
		)
		(duplicate_pad_numbers_are_jumpers no)
		(fp_line
			(start 0.7874 0.4064)
			(end -0.7874 0.4064)
			(stroke
				(width 0.1524)
				(type default)
			)
			(layer "F.SilkS")
		)
		(fp_line
			(start 0.7874 -0.4064)
			(end 0.7874 0.4064)
			(stroke
				(width 0.1524)
				(type default)
			)
			(layer "F.SilkS")
		)
		(fp_line
			(start -0.7874 0.4064)
			(end -0.7874 -0.4064)
			(stroke
				(width 0.1524)
				(type default)
			)
			(layer "F.SilkS")
		)
		(fp_line
			(start -0.7874 -0.4064)
			(end 0.7874 -0.4064)
			(stroke
				(width 0.1524)
				(type default)
			)
			(layer "F.SilkS")
		)
		(fp_poly
			(pts
				(xy -0.508 0.2794) (xy -0.508 0.2286) (xy -0.635 0.2286) (xy -0.635 -0.254) (xy -0.5334 -0.254)
				(xy -0.5334 -0.2794) (xy 0.5334 -0.2794) (xy 0.5334 -0.254) (xy 0.635 -0.254) (xy 0.635 0.254) (xy 0.5334 0.254)
				(xy 0.5334 0.2794)
			)
			(stroke
				(width 0)
				(type default)
			)
			(fill no)
			(layer "F.CrtYd")
		)
		(pad "1" smd rect
			(at 0.40005 0 180)
			(size 0.4572 0.508)
			(layers "F.Cu" "F.Mask" "F.Paste")
			(net "FM_CPLD_NODE1_JTAG_POK_R_L")
		)
		(pad "2" smd rect
			(at -0.40005 0 180)
			(size 0.4572 0.508)
			(layers "F.Cu" "F.Mask" "F.Paste")
			(net "FM_CPLD_NODE1_JTAG_POK_L")
		)
	)
	(footprint ""
		(layer "F.Cu")
		(at 171.879006 -93.877892 180)
		(property "Reference" "R526"
			(at -3.550158 -0.561594 90)
			(unlocked yes)
			(layer "F.SilkS")
			(effects
				(font
					(size 0.7874 0.5842)
					(thickness 0.1524)
				)
				(justify left)
			)
		)
		(property "Value" ""
			(at 0 0 180)
			(layer "F.Fab")
			(effects
				(font
					(size 1.27 1.27)
				)
			)
		)
		(duplicate_pad_numbers_are_jumpers no)
		(fp_line
			(start 0.7874 0.4064)
			(end -0.7874 0.4064)
			(stroke
				(width 0.1524)
				(type default)
			)
			(layer "F.SilkS")
		)
		(fp_line
			(start 0.7874 -0.4064)
			(end 0.7874 0.4064)
			(stroke
				(width 0.1524)
				(type default)
			)
			(layer "F.SilkS")
		)
		(fp_line
			(start -0.7874 0.4064)
			(end -0.7874 -0.4064)
			(stroke
				(width 0.1524)
				(type default)
			)
			(layer "F.SilkS")
		)
		(fp_line
			(start -0.7874 -0.4064)
			(end 0.7874 -0.4064)
			(stroke
				(width 0.1524)
				(type default)
			)
			(layer "F.SilkS")
		)
		(fp_poly
			(pts
				(xy -0.508 0.2794) (xy -0.508 0.2286) (xy -0.635 0.2286) (xy -0.635 -0.254) (xy -0.5334 -0.254)
				(xy -0.5334 -0.2794) (xy 0.5334 -0.2794) (xy 0.5334 -0.254) (xy 0.635 -0.254) (xy 0.635 0.254) (xy 0.5334 0.254)
				(xy 0.5334 0.2794)
			)
			(stroke
				(width 0)
				(type default)
			)
			(fill no)
			(layer "F.CrtYd")
		)
		(pad "1" smd rect
			(at 0.40005 0 180)
			(size 0.4572 0.508)
			(layers "F.Cu" "F.Mask" "F.Paste")
			(net "USB_NODE1_RREF")
		)
		(pad "2" smd rect
			(at -0.40005 0 180)
			(size 0.4572 0.508)
			(layers "F.Cu" "F.Mask" "F.Paste")
			(net "GND")
		)
	)
	(footprint ""
		(layer "F.Cu")
		(at 151.62276 -188.126624 -90)
		(property "Reference" "R981"
			(at -5.519674 2.935732 90)
			(unlocked yes)
			(layer "F.SilkS")
			(effects
				(font
					(size 0.7874 0.5842)
					(thickness 0.1524)
				)
				(justify left)
			)
		)
		(property "Value" ""
			(at 0 0 270)
			(layer "F.Fab")
			(effects
				(font
					(size 1.27 1.27)
				)
			)
		)
		(duplicate_pad_numbers_are_jumpers no)
		(fp_line
			(start -0.7874 0.4064)
			(end -0.7874 -0.4064)
			(stroke
				(width 0.1524)
				(type default)
			)
			(layer "F.SilkS")
		)
		(fp_line
			(start 0.7874 0.4064)
			(end -0.7874 0.4064)
			(stroke
				(width 0.1524)
				(type default)
			)
			(layer "F.SilkS")
		)
		(fp_line
			(start -0.7874 -0.4064)
			(end 0.7874 -0.4064)
			(stroke
				(width 0.1524)
				(type default)
			)
			(layer "F.SilkS")
		)
		(fp_line
			(start 0.7874 -0.4064)
			(end 0.7874 0.4064)
			(stroke
				(width 0.1524)
				(type default)
			)
			(layer "F.SilkS")
		)
		(fp_poly
			(pts
				(xy -0.508 0.2794) (xy -0.508 0.2286) (xy -0.635 0.2286) (xy -0.635 -0.254) (xy -0.5334 -0.254)
				(xy -0.5334 -0.2794) (xy 0.5334 -0.2794) (xy 0.5334 -0.254) (xy 0.635 -0.254) (xy 0.635 0.254) (xy 0.5334 0.254)
				(xy 0.5334 0.2794)
			)
			(stroke
				(width 0)
				(type default)
			)
			(fill no)
			(layer "F.CrtYd")
		)
		(pad "1" smd rect
			(at 0.40005 0 270)
			(size 0.4572 0.508)
			(layers "F.Cu" "F.Mask" "F.Paste")
			(net "UART_T12_NODE1_RXD")
		)
		(pad "2" smd rect
			(at -0.40005 0 270)
			(size 0.4572 0.508)
			(layers "F.Cu" "F.Mask" "F.Paste")
			(net "UART_T12_NODE1_RXD_R")
		)
	)
	(footprint ""
		(layer "F.Cu")
		(at 164.384482 -73.331324)
		(property "Reference" "C852"
			(at 2.60731 -0.278384 0)
			(unlocked yes)
			(layer "F.SilkS")
			(effects
				(font
					(size 0.7874 0.5842)
					(thickness 0.1524)
				)
				(justify left)
			)
		)
		(property "Value" ""
			(at 0 0 0)
			(layer "F.Fab")
			(effects
				(font
					(size 1.27 1.27)
				)
			)
		)
		(duplicate_pad_numbers_are_jumpers no)
		(fp_line
			(start -0.7874 -0.4064)
			(end 0.7874 -0.4064)
			(stroke
				(width 0.1524)
				(type default)
			)
			(layer "F.SilkS")
		)
		(fp_line
			(start -0.7874 0.4064)
			(end -0.7874 -0.4064)
			(stroke
				(width 0.1524)
				(type default)
			)
			(layer "F.SilkS")
		)
		(fp_line
			(start 0 0.381)
			(end 0 -0.381)
			(stroke
				(width 0.1524)
				(type default)
			)
			(layer "F.SilkS")
		)
		(fp_line
			(start 0.7874 -0.4064)
			(end 0.7874 0.4064)
			(stroke
				(width 0.1524)
				(type default)
			)
			(layer "F.SilkS")
		)
		(fp_line
			(start 0.7874 0.4064)
			(end -0.7874 0.4064)
			(stroke
				(width 0.1524)
				(type default)
			)
			(layer "F.SilkS")
		)
		(fp_poly
			(pts
				(xy -0.5334 0.254) (xy -0.635 0.254) (xy -0.635 0.2286) (xy -0.635 -0.254) (xy -0.5334 -0.254) (xy -0.5334 -0.2794)
				(xy 0.5334 -0.2794) (xy 0.5334 -0.254) (xy 0.635 -0.254) (xy 0.635 0.254) (xy 0.5334 0.254) (xy 0.5334 0.2794)
				(xy -0.508 0.2794) (xy -0.5334 0.2794)
			)
			(stroke
				(width 0)
				(type default)
			)
			(fill no)
			(layer "F.CrtYd")
		)
		(pad "1" smd rect
			(at 0.40005 0)
			(size 0.4572 0.508)
			(layers "F.Cu" "F.Mask" "F.Paste")
			(net "N47241340")
		)
		(pad "2" smd rect
			(at -0.40005 0)
			(size 0.4572 0.508)
			(layers "F.Cu" "F.Mask" "F.Paste")
			(net "GND")
		)
	)
	(footprint ""
		(layer "F.Cu")
		(at 33.639252 -179.990242 180)
		(property "Reference" "U100"
			(at 1.857502 -4.473448 90)
			(unlocked yes)
			(layer "F.SilkS")
			(effects
				(font
					(size 0.7874 0.5842)
					(thickness 0.1524)
				)
				(justify left)
			)
		)
		(property "Value" ""
			(at 0 0 180)
			(layer "F.Fab")
			(effects
				(font
					(size 1.27 1.27)
				)
			)
		)
		(duplicate_pad_numbers_are_jumpers no)
		(fp_line
			(start 1.550924 1.340104)
			(end -1.550924 1.340104)
			(stroke
				(width 0.1524)
				(type default)
			)
			(layer "F.SilkS")
		)
		(fp_line
			(start 1.550924 -1.340104)
			(end 1.550924 1.340104)
			(stroke
				(width 0.1524)
				(type default)
			)
			(layer "F.SilkS")
		)
		(fp_line
			(start -0.929894 0)
			(end -1.550924 -0.499872)
			(stroke
				(width 0.1524)
				(type default)
			)
			(layer "F.SilkS")
		)
		(fp_line
			(start -1.550924 1.340104)
			(end -1.550924 0.499872)
			(stroke
				(width 0.1524)
				(type default)
			)
			(layer "F.SilkS")
		)
		(fp_line
			(start -1.550924 0.499872)
			(end -0.929894 0)
			(stroke
				(width 0.1524)
				(type default)
			)
			(layer "F.SilkS")
		)
		(fp_line
			(start -1.550924 -0.499872)
			(end -1.550924 -1.340104)
			(stroke
				(width 0.1524)
				(type default)
			)
			(layer "F.SilkS")
		)
		(fp_line
			(start -1.550924 -1.340104)
			(end 1.550924 -1.340104)
			(stroke
				(width 0.1524)
				(type default)
			)
			(layer "F.SilkS")
		)
		(fp_poly
			(pts
				(xy -1.500124 1.3716) (xy -1.500124 0.4572) (xy -0.999998 0) (xy -1.500124 -0.4572) (xy -1.500124 -1.3716)
				(xy 1.500124 -1.3716) (xy 1.500124 1.3716)
			)
			(stroke
				(width 0)
				(type default)
			)
			(fill yes)
			(layer "F.SilkS")
		)
		(fp_poly
			(pts
				(xy -1.1684 2.9464) (xy -1.1684 1.3462) (xy -1.5494 1.3462) (xy -1.5494 -1.3462) (xy -1.1684 -1.3462)
				(xy -1.1684 -2.9464) (xy 1.1684 -2.9464) (xy 1.1684 -1.3462) (xy 1.5748 -1.3462) (xy 1.5748 1.3462)
				(xy 1.1684 1.3462) (xy 1.1684 2.9464)
			)
			(stroke
				(width 0)
				(type default)
			)
			(fill no)
			(layer "F.CrtYd")
		)
		(fp_line
			(start 1.5748 1.3462)
			(end -1.5494 1.3462)
			(stroke
				(width 0.1)
				(type default)
			)
			(layer "F.Fab")
		)
		(fp_line
			(start 1.5748 -1.3462)
			(end 1.5748 1.3462)
			(stroke
				(width 0.1)
				(type default)
			)
			(layer "F.Fab")
		)
		(fp_line
			(start -1.5494 1.3462)
			(end -1.5494 0)
			(stroke
				(width 0.1)
				(type default)
			)
			(layer "F.Fab")
		)
		(fp_line
			(start -1.5494 0)
			(end -1.5494 -1.3462)
			(stroke
				(width 0.1)
				(type default)
			)
			(layer "F.Fab")
		)
		(fp_line
			(start -1.5494 -1.3462)
			(end 1.5748 -1.3462)
			(stroke
				(width 0.1)
				(type default)
			)
			(layer "F.Fab")
		)
		(pad "1" smd rect
			(at -0.999998 2.22504 180)
			(size 0.2794 1.4478)
			(layers "F.Cu" "F.Mask" "F.Paste")
			(net "P12V_PDB")
		)
		(pad "2" smd rect
			(at -0.499872 2.22504 180)
			(size 0.2794 1.4478)
			(layers "F.Cu" "F.Mask" "F.Paste")
			(net "VSENSE_HSC_NODE1")
		)
		(pad "3" smd rect
			(at 0 2.22504 180)
			(size 0.2794 1.4478)
			(layers "F.Cu" "F.Mask" "F.Paste")
			(net "P12V_AUX_EN")
		)
		(pad "4" smd rect
			(at 0.499872 2.22504 180)
			(size 0.2794 1.4478)
			(layers "F.Cu" "F.Mask" "F.Paste")
			(net "AGND_HSC_NODE1")
		)
		(pad "5" smd rect
			(at 0.999998 2.22504 180)
			(size 0.2794 1.4478)
			(layers "F.Cu" "F.Mask" "F.Paste")
			(net "VR_HSC_NODE1_TIMER")
		)
		(pad "6" smd rect
			(at 0.999998 -2.22504 180)
			(size 0.2794 1.4478)
			(layers "F.Cu" "F.Mask" "F.Paste")
			(net "SMB_CPU_NODE1_BMC_CLK")
		)
		(pad "7" smd rect
			(at 0.499872 -2.22504 180)
			(size 0.2794 1.4478)
			(layers "F.Cu" "F.Mask" "F.Paste")
			(net "SMB_CPU_NODE1_BMC_DAT")
		)
		(pad "8" smd rect
			(at 0 -2.22504 180)
			(size 0.2794 1.4478)
			(layers "F.Cu" "F.Mask" "F.Paste")
			(net "AGND_HSC_NODE1")
		)
		(pad "9" smd rect
			(at -0.499872 -2.22504 180)
			(size 0.2794 1.4478)
			(layers "F.Cu" "F.Mask" "F.Paste")
			(net "VR_HSC_NODE1_GATE_R")
		)
		(pad "10" smd rect
			(at -0.999998 -2.22504 180)
			(size 0.2794 1.4478)
			(layers "F.Cu" "F.Mask" "F.Paste")
			(net "SMB_BMC_NODE1_HSC_ALERT_R_L")
		)
	)
)
